(kicad_pcb
	(version 20260206)
	(generator "pcbnew")
	(generator_version "10.0")
	(general
		(thickness 1.6)
		(legacy_teardrops no)
	)
	(paper "A4")
	(title_block
		(title "01162023_DA0F0TEBIF0_F0T_Expander_BD_F_brd_V02_OCP.brd")
		(comment 1 "Grand Teton / footprints 6701-6706 of 9728")
	)
	(layers
		(0 "F.Cu" signal "TOP")
		(4 "In1.Cu" signal "GND")
		(6 "In2.Cu" signal "VCC")
		(8 "In3.Cu" signal "VCC1")
		(10 "In4.Cu" signal "GND1")
		(12 "In5.Cu" signal "IN1")
		(14 "In6.Cu" signal "GND2")
		(16 "In7.Cu" signal "IN2")
		(18 "In8.Cu" signal "GND3")
		(20 "In9.Cu" signal "IN3")
		(22 "In10.Cu" signal "GND4")
		(24 "In11.Cu" signal "IN4")
		(26 "In12.Cu" signal "GND5")
		(28 "In13.Cu" signal "IN5")
		(30 "In14.Cu" signal "GND6")
		(32 "In15.Cu" signal "IN6")
		(34 "In16.Cu" signal "GND7")
		(2 "B.Cu" signal "BOTTOM")
		(9 "F.Adhes" user "F.Adhesive")
		(11 "B.Adhes" user "B.Adhesive")
		(13 "F.Paste" user "Package Geometry/Pastemask Top")
		(15 "B.Paste" user "Package Geometry/Pastemask Bottom")
		(5 "F.SilkS" user "Ref Des/Silkscreen Top")
		(7 "B.SilkS" user "Ref Des/Silkscreen Bottom")
		(1 "F.Mask" user "Board Geometry/Soldermask Top")
		(3 "B.Mask" user "Board Geometry/Soldermask Bottom")
		(17 "Dwgs.User" user "User.Drawings")
		(19 "Cmts.User" user "User.Comments")
		(21 "Eco1.User" user "User.Eco1")
		(23 "Eco2.User" user "User.Eco2")
		(25 "Edge.Cuts" user "Board Geometry/Outline")
		(27 "Margin" user)
		(31 "F.CrtYd" user "Package Geometry/Place Bound Top")
		(29 "B.CrtYd" user "Package Geometry/Place Bound Bottom")
		(35 "F.Fab" user "Ref Des/Assembly Top")
		(33 "B.Fab" user "Ref Des/Assembly Bottom")
	)
	(footprint ""
		(layer "F.Cu")
		(at 259.021072 -357.383842 90)
		(property "Reference" "PD2"
			(at 1.544574 4.171442 0)
			(unlocked yes)
			(layer "F.SilkS")
			(effects
				(font
					(size 0.7874 0.5842)
					(thickness 0.1524)
				)
			)
		)
		(property "Value" ""
			(at 0 0 90)
			(layer "F.Fab")
			(effects
				(font
					(size 1.27 1.27)
				)
			)
		)
		(duplicate_pad_numbers_are_jumpers no)
		(fp_line
			(start 3.541776 -2.54)
			(end 3.541776 2.54)
			(stroke
				(width 0.1524)
				(type default)
			)
			(layer "F.SilkS")
		)
		(fp_line
			(start -3.539744 -2.54)
			(end 3.541776 -2.54)
			(stroke
				(width 0.1524)
				(type default)
			)
			(layer "F.SilkS")
		)
		(fp_line
			(start 3.541776 2.54)
			(end -3.539744 2.54)
			(stroke
				(width 0.1524)
				(type default)
			)
			(layer "F.SilkS")
		)
		(fp_line
			(start -3.539744 2.54)
			(end -3.539744 -2.54)
			(stroke
				(width 0.1524)
				(type default)
			)
			(layer "F.SilkS")
		)
		(fp_poly
			(pts
				(xy -4.699 0.531876) (xy -4.699 1.547876) (xy -3.683 1.039876)
			)
			(stroke
				(width 0)
				(type default)
			)
			(fill yes)
			(layer "F.SilkS")
		)
		(fp_line
			(start 3.074924 -2.175002)
			(end 3.074924 2.175002)
			(stroke
				(width 0.1)
				(type default)
			)
			(layer "F.Fab")
		)
		(fp_line
			(start -3.074924 -2.175002)
			(end 3.074924 -2.175002)
			(stroke
				(width 0.1)
				(type default)
			)
			(layer "F.Fab")
		)
		(fp_line
			(start 3.074924 2.175002)
			(end -3.074924 2.175002)
			(stroke
				(width 0.1)
				(type default)
			)
			(layer "F.Fab")
		)
		(fp_line
			(start -3.074924 2.175002)
			(end -3.074924 -2.175002)
			(stroke
				(width 0.1)
				(type default)
			)
			(layer "F.Fab")
		)
		(fp_poly
			(pts
				(xy -4.699 0.531876) (xy -4.699 1.547876) (xy -3.683 1.039876)
			)
			(stroke
				(width 0)
				(type default)
			)
			(fill yes)
			(layer "F.Fab")
		)
		(pad "1" smd rect
			(at -2.765044 1.039876 270)
			(size 1.27 1.4224)
			(layers "F.Cu" "F.Mask" "F.Paste")
			(net "GND")
		)
		(pad "2" smd rect
			(at -2.765044 -1.039876 270)
			(size 1.27 1.4224)
			(layers "F.Cu" "F.Mask" "F.Paste")
			(net "GND")
		)
		(pad "K" smd rect
			(at 1.039876 0 270)
			(size 4.7244 4.8006)
			(layers "F.Cu" "F.Mask" "F.Paste")
			(net "P12V_AUX")
		)
	)
	(footprint ""
		(layer "F.Cu")
		(at 13.503402 -285.730442)
		(property "Reference" "PC216"
			(at 0 0 0)
			(layer "F.SilkS")
			(hide yes)
			(effects
				(font
					(size 1.27 1.27)
				)
			)
		)
		(property "Value" ""
			(at 0 0 0)
			(layer "F.Fab")
			(effects
				(font
					(size 1.27 1.27)
				)
			)
		)
		(duplicate_pad_numbers_are_jumpers no)
		(fp_line
			(start -0.7874 -0.4064)
			(end 0.7874 -0.4064)
			(stroke
				(width 0.1524)
				(type default)
			)
			(layer "F.SilkS")
		)
		(fp_line
			(start -0.7874 0.4064)
			(end -0.7874 -0.4064)
			(stroke
				(width 0.1524)
				(type default)
			)
			(layer "F.SilkS")
		)
		(fp_line
			(start 0.7874 -0.4064)
			(end 0.7874 0.4064)
			(stroke
				(width 0.1524)
				(type default)
			)
			(layer "F.SilkS")
		)
		(fp_line
			(start 0.7874 0.4064)
			(end -0.7874 0.4064)
			(stroke
				(width 0.1524)
				(type default)
			)
			(layer "F.SilkS")
		)
		(fp_line
			(start -0.67945 -0.305054)
			(end -0.12065 -0.305054)
			(stroke
				(width 0.1)
				(type default)
			)
			(layer "F.Fab")
		)
		(fp_line
			(start -0.67945 0.3048)
			(end -0.67945 -0.305054)
			(stroke
				(width 0.1)
				(type default)
			)
			(layer "F.Fab")
		)
		(fp_line
			(start -0.12065 -0.305054)
			(end -0.12065 -0.2794)
			(stroke
				(width 0.1)
				(type default)
			)
			(layer "F.Fab")
		)
		(fp_line
			(start -0.12065 -0.2794)
			(end 0.12065 -0.2794)
			(stroke
				(width 0.1)
				(type default)
			)
			(layer "F.Fab")
		)
		(fp_line
			(start -0.12065 0.2794)
			(end -0.12065 0.3048)
			(stroke
				(width 0.1)
				(type default)
			)
			(layer "F.Fab")
		)
		(fp_line
			(start -0.12065 0.3048)
			(end -0.67945 0.3048)
			(stroke
				(width 0.1)
				(type default)
			)
			(layer "F.Fab")
		)
		(fp_line
			(start 0.120396 0.2794)
			(end -0.12065 0.2794)
			(stroke
				(width 0.1)
				(type default)
			)
			(layer "F.Fab")
		)
		(fp_line
			(start 0.120396 0.3048)
			(end 0.120396 0.2794)
			(stroke
				(width 0.1)
				(type default)
			)
			(layer "F.Fab")
		)
		(fp_line
			(start 0.12065 -0.3048)
			(end 0.67945 -0.3048)
			(stroke
				(width 0.1)
				(type default)
			)
			(layer "F.Fab")
		)
		(fp_line
			(start 0.12065 -0.2794)
			(end 0.12065 -0.3048)
			(stroke
				(width 0.1)
				(type default)
			)
			(layer "F.Fab")
		)
		(fp_line
			(start 0.67945 -0.3048)
			(end 0.67945 0.3048)
			(stroke
				(width 0.1)
				(type default)
			)
			(layer "F.Fab")
		)
		(fp_line
			(start 0.67945 0.3048)
			(end 0.120396 0.3048)
			(stroke
				(width 0.1)
				(type default)
			)
			(layer "F.Fab")
		)
		(pad "1" smd circle
			(at -0.40005 0)
			(size 0 0)
			(layers "F.Cu" "F.Mask" "F.Paste")
			(net "P1V25_PEX0_R")
		)
		(pad "2" smd circle
			(at 0.40005 0)
			(size 0 0)
			(layers "F.Cu" "F.Mask" "F.Paste")
			(net "GND")
		)
	)
	(footprint ""
		(layer "F.Cu")
		(at 336.551778 -93.154246 -90)
		(property "Reference" "R3509"
			(at 0 0 270)
			(layer "F.SilkS")
			(hide yes)
			(effects
				(font
					(size 1.27 1.27)
				)
			)
		)
		(property "Value" ""
			(at 0 0 270)
			(layer "F.Fab")
			(effects
				(font
					(size 1.27 1.27)
				)
			)
		)
		(duplicate_pad_numbers_are_jumpers no)
		(fp_line
			(start -0.7874 0.4064)
			(end -0.7874 -0.4064)
			(stroke
				(width 0.1524)
				(type default)
			)
			(layer "F.SilkS")
		)
		(fp_line
			(start 0.7874 0.4064)
			(end -0.7874 0.4064)
			(stroke
				(width 0.1524)
				(type default)
			)
			(layer "F.SilkS")
		)
		(fp_line
			(start -0.7874 -0.4064)
			(end 0.7874 -0.4064)
			(stroke
				(width 0.1524)
				(type default)
			)
			(layer "F.SilkS")
		)
		(fp_line
			(start 0.7874 -0.4064)
			(end 0.7874 0.4064)
			(stroke
				(width 0.1524)
				(type default)
			)
			(layer "F.SilkS")
		)
		(fp_line
			(start -0.67945 0.3048)
			(end -0.67945 -0.305054)
			(stroke
				(width 0.1)
				(type default)
			)
			(layer "F.Fab")
		)
		(fp_line
			(start -0.12065 0.3048)
			(end -0.67945 0.3048)
			(stroke
				(width 0.1)
				(type default)
			)
			(layer "F.Fab")
		)
		(fp_line
			(start 0.120396 0.3048)
			(end 0.120396 0.2794)
			(stroke
				(width 0.1)
				(type default)
			)
			(layer "F.Fab")
		)
		(fp_line
			(start 0.67945 0.3048)
			(end 0.120396 0.3048)
			(stroke
				(width 0.1)
				(type default)
			)
			(layer "F.Fab")
		)
		(fp_line
			(start -0.12065 0.2794)
			(end -0.12065 0.3048)
			(stroke
				(width 0.1)
				(type default)
			)
			(layer "F.Fab")
		)
		(fp_line
			(start 0.120396 0.2794)
			(end -0.12065 0.2794)
			(stroke
				(width 0.1)
				(type default)
			)
			(layer "F.Fab")
		)
		(fp_line
			(start -0.12065 -0.2794)
			(end 0.12065 -0.2794)
			(stroke
				(width 0.1)
				(type default)
			)
			(layer "F.Fab")
		)
		(fp_line
			(start 0.12065 -0.2794)
			(end 0.12065 -0.3048)
			(stroke
				(width 0.1)
				(type default)
			)
			(layer "F.Fab")
		)
		(fp_line
			(start 0.12065 -0.3048)
			(end 0.67945 -0.3048)
			(stroke
				(width 0.1)
				(type default)
			)
			(layer "F.Fab")
		)
		(fp_line
			(start 0.67945 -0.3048)
			(end 0.67945 0.3048)
			(stroke
				(width 0.1)
				(type default)
			)
			(layer "F.Fab")
		)
		(fp_line
			(start -0.67945 -0.305054)
			(end -0.12065 -0.305054)
			(stroke
				(width 0.1)
				(type default)
			)
			(layer "F.Fab")
		)
		(fp_line
			(start -0.12065 -0.305054)
			(end -0.12065 -0.2794)
			(stroke
				(width 0.1)
				(type default)
			)
			(layer "F.Fab")
		)
		(pad "1" smd circle
			(at -0.40005 0 270)
			(size 0 0)
			(layers "F.Cu" "F.Mask" "F.Paste")
			(net "P3V3")
		)
		(pad "2" smd circle
			(at 0.40005 0 270)
			(size 0 0)
			(layers "F.Cu" "F.Mask" "F.Paste")
			(net "PU_9ZXL0851_8_15_100M")
		)
	)
	(footprint ""
		(layer "F.Cu")
		(at 48.027844 -35.876738)
		(property "Reference" "R5882"
			(at 0 0 0)
			(layer "F.SilkS")
			(hide yes)
			(effects
				(font
					(size 1.27 1.27)
				)
			)
		)
		(property "Value" ""
			(at 0 0 0)
			(layer "F.Fab")
			(effects
				(font
					(size 1.27 1.27)
				)
			)
		)
		(duplicate_pad_numbers_are_jumpers no)
		(fp_line
			(start -0.7874 -0.4064)
			(end 0.7874 -0.4064)
			(stroke
				(width 0.1524)
				(type default)
			)
			(layer "F.SilkS")
		)
		(fp_line
			(start -0.7874 0.4064)
			(end -0.7874 -0.4064)
			(stroke
				(width 0.1524)
				(type default)
			)
			(layer "F.SilkS")
		)
		(fp_line
			(start 0.7874 -0.4064)
			(end 0.7874 0.4064)
			(stroke
				(width 0.1524)
				(type default)
			)
			(layer "F.SilkS")
		)
		(fp_line
			(start 0.7874 0.4064)
			(end -0.7874 0.4064)
			(stroke
				(width 0.1524)
				(type default)
			)
			(layer "F.SilkS")
		)
		(fp_line
			(start -0.67945 -0.305054)
			(end -0.12065 -0.305054)
			(stroke
				(width 0.1)
				(type default)
			)
			(layer "F.Fab")
		)
		(fp_line
			(start -0.67945 0.3048)
			(end -0.67945 -0.305054)
			(stroke
				(width 0.1)
				(type default)
			)
			(layer "F.Fab")
		)
		(fp_line
			(start -0.12065 -0.305054)
			(end -0.12065 -0.2794)
			(stroke
				(width 0.1)
				(type default)
			)
			(layer "F.Fab")
		)
		(fp_line
			(start -0.12065 -0.2794)
			(end 0.12065 -0.2794)
			(stroke
				(width 0.1)
				(type default)
			)
			(layer "F.Fab")
		)
		(fp_line
			(start -0.12065 0.2794)
			(end -0.12065 0.3048)
			(stroke
				(width 0.1)
				(type default)
			)
			(layer "F.Fab")
		)
		(fp_line
			(start -0.12065 0.3048)
			(end -0.67945 0.3048)
			(stroke
				(width 0.1)
				(type default)
			)
			(layer "F.Fab")
		)
		(fp_line
			(start 0.120396 0.2794)
			(end -0.12065 0.2794)
			(stroke
				(width 0.1)
				(type default)
			)
			(layer "F.Fab")
		)
		(fp_line
			(start 0.120396 0.3048)
			(end 0.120396 0.2794)
			(stroke
				(width 0.1)
				(type default)
			)
			(layer "F.Fab")
		)
		(fp_line
			(start 0.12065 -0.3048)
			(end 0.67945 -0.3048)
			(stroke
				(width 0.1)
				(type default)
			)
			(layer "F.Fab")
		)
		(fp_line
			(start 0.12065 -0.2794)
			(end 0.12065 -0.3048)
			(stroke
				(width 0.1)
				(type default)
			)
			(layer "F.Fab")
		)
		(fp_line
			(start 0.67945 -0.3048)
			(end 0.67945 0.3048)
			(stroke
				(width 0.1)
				(type default)
			)
			(layer "F.Fab")
		)
		(fp_line
			(start 0.67945 0.3048)
			(end 0.120396 0.3048)
			(stroke
				(width 0.1)
				(type default)
			)
			(layer "F.Fab")
		)
		(pad "1" smd circle
			(at -0.40005 0)
			(size 0 0)
			(layers "F.Cu" "F.Mask" "F.Paste")
			(net "PWRGD_P3V3_SSD2_D")
		)
		(pad "2" smd circle
			(at 0.40005 0)
			(size 0 0)
			(layers "F.Cu" "F.Mask" "F.Paste")
			(net "PWRGD_P3V3_SSD2_R")
		)
	)
	(footprint ""
		(layer "F.Cu")
		(at 340.995 -234.061 90)
		(property "Reference" "R3594"
			(at 0 0 90)
			(layer "F.SilkS")
			(hide yes)
			(effects
				(font
					(size 1.27 1.27)
				)
			)
		)
		(property "Value" ""
			(at 0 0 90)
			(layer "F.Fab")
			(effects
				(font
					(size 1.27 1.27)
				)
			)
		)
		(duplicate_pad_numbers_are_jumpers no)
		(fp_line
			(start 0.7874 -0.4064)
			(end 0.7874 0.4064)
			(stroke
				(width 0.1524)
				(type default)
			)
			(layer "F.SilkS")
		)
		(fp_line
			(start -0.7874 -0.4064)
			(end 0.7874 -0.4064)
			(stroke
				(width 0.1524)
				(type default)
			)
			(layer "F.SilkS")
		)
		(fp_line
			(start 0.7874 0.4064)
			(end -0.7874 0.4064)
			(stroke
				(width 0.1524)
				(type default)
			)
			(layer "F.SilkS")
		)
		(fp_line
			(start -0.7874 0.4064)
			(end -0.7874 -0.4064)
			(stroke
				(width 0.1524)
				(type default)
			)
			(layer "F.SilkS")
		)
		(fp_line
			(start -0.12065 -0.305054)
			(end -0.12065 -0.2794)
			(stroke
				(width 0.1)
				(type default)
			)
			(layer "F.Fab")
		)
		(fp_line
			(start -0.67945 -0.305054)
			(end -0.12065 -0.305054)
			(stroke
				(width 0.1)
				(type default)
			)
			(layer "F.Fab")
		)
		(fp_line
			(start 0.67945 -0.3048)
			(end 0.67945 0.3048)
			(stroke
				(width 0.1)
				(type default)
			)
			(layer "F.Fab")
		)
		(fp_line
			(start 0.12065 -0.3048)
			(end 0.67945 -0.3048)
			(stroke
				(width 0.1)
				(type default)
			)
			(layer "F.Fab")
		)
		(fp_line
			(start 0.12065 -0.2794)
			(end 0.12065 -0.3048)
			(stroke
				(width 0.1)
				(type default)
			)
			(layer "F.Fab")
		)
		(fp_line
			(start -0.12065 -0.2794)
			(end 0.12065 -0.2794)
			(stroke
				(width 0.1)
				(type default)
			)
			(layer "F.Fab")
		)
		(fp_line
			(start 0.120396 0.2794)
			(end -0.12065 0.2794)
			(stroke
				(width 0.1)
				(type default)
			)
			(layer "F.Fab")
		)
		(fp_line
			(start -0.12065 0.2794)
			(end -0.12065 0.3048)
			(stroke
				(width 0.1)
				(type default)
			)
			(layer "F.Fab")
		)
		(fp_line
			(start 0.67945 0.3048)
			(end 0.120396 0.3048)
			(stroke
				(width 0.1)
				(type default)
			)
			(layer "F.Fab")
		)
		(fp_line
			(start 0.120396 0.3048)
			(end 0.120396 0.2794)
			(stroke
				(width 0.1)
				(type default)
			)
			(layer "F.Fab")
		)
		(fp_line
			(start -0.12065 0.3048)
			(end -0.67945 0.3048)
			(stroke
				(width 0.1)
				(type default)
			)
			(layer "F.Fab")
		)
		(fp_line
			(start -0.67945 0.3048)
			(end -0.67945 -0.305054)
			(stroke
				(width 0.1)
				(type default)
			)
			(layer "F.Fab")
		)
		(pad "1" smd circle
			(at -0.40005 0 90)
			(size 0 0)
			(layers "F.Cu" "F.Mask" "F.Paste")
			(net "SSD1_PWR_EN")
		)
		(pad "2" smd circle
			(at 0.40005 0 90)
			(size 0 0)
			(layers "F.Cu" "F.Mask" "F.Paste")
			(net "SSD1_PWR_EN_R")
		)
	)
	(footprint ""
		(layer "F.Cu")
		(at 462.465674 -275.62683)
		(property "Reference" "R803"
			(at 0 0 0)
			(layer "F.SilkS")
			(hide yes)
			(effects
				(font
					(size 1.27 1.27)
				)
			)
		)
		(property "Value" ""
			(at 0 0 0)
			(layer "F.Fab")
			(effects
				(font
					(size 1.27 1.27)
				)
			)
		)
		(duplicate_pad_numbers_are_jumpers no)
		(fp_line
			(start -0.7874 -0.4064)
			(end 0.7874 -0.4064)
			(stroke
				(width 0.1524)
				(type default)
			)
			(layer "F.SilkS")
		)
		(fp_line
			(start -0.7874 0.4064)
			(end -0.7874 -0.4064)
			(stroke
				(width 0.1524)
				(type default)
			)
			(layer "F.SilkS")
		)
		(fp_line
			(start 0.7874 -0.4064)
			(end 0.7874 0.4064)
			(stroke
				(width 0.1524)
				(type default)
			)
			(layer "F.SilkS")
		)
		(fp_line
			(start 0.7874 0.4064)
			(end -0.7874 0.4064)
			(stroke
				(width 0.1524)
				(type default)
			)
			(layer "F.SilkS")
		)
		(fp_line
			(start -0.67945 -0.305054)
			(end -0.12065 -0.305054)
			(stroke
				(width 0.1)
				(type default)
			)
			(layer "F.Fab")
		)
		(fp_line
			(start -0.67945 0.3048)
			(end -0.67945 -0.305054)
			(stroke
				(width 0.1)
				(type default)
			)
			(layer "F.Fab")
		)
		(fp_line
			(start -0.12065 -0.305054)
			(end -0.12065 -0.2794)
			(stroke
				(width 0.1)
				(type default)
			)
			(layer "F.Fab")
		)
		(fp_line
			(start -0.12065 -0.2794)
			(end 0.12065 -0.2794)
			(stroke
				(width 0.1)
				(type default)
			)
			(layer "F.Fab")
		)
		(fp_line
			(start -0.12065 0.2794)
			(end -0.12065 0.3048)
			(stroke
				(width 0.1)
				(type default)
			)
			(layer "F.Fab")
		)
		(fp_line
			(start -0.12065 0.3048)
			(end -0.67945 0.3048)
			(stroke
				(width 0.1)
				(type default)
			)
			(layer "F.Fab")
		)
		(fp_line
			(start 0.120396 0.2794)
			(end -0.12065 0.2794)
			(stroke
				(width 0.1)
				(type default)
			)
			(layer "F.Fab")
		)
		(fp_line
			(start 0.120396 0.3048)
			(end 0.120396 0.2794)
			(stroke
				(width 0.1)
				(type default)
			)
			(layer "F.Fab")
		)
		(fp_line
			(start 0.12065 -0.3048)
			(end 0.67945 -0.3048)
			(stroke
				(width 0.1)
				(type default)
			)
			(layer "F.Fab")
		)
		(fp_line
			(start 0.12065 -0.2794)
			(end 0.12065 -0.3048)
			(stroke
				(width 0.1)
				(type default)
			)
			(layer "F.Fab")
		)
		(fp_line
			(start 0.67945 -0.3048)
			(end 0.67945 0.3048)
			(stroke
				(width 0.1)
				(type default)
			)
			(layer "F.Fab")
		)
		(fp_line
			(start 0.67945 0.3048)
			(end 0.120396 0.3048)
			(stroke
				(width 0.1)
				(type default)
			)
			(layer "F.Fab")
		)
		(pad "1" smd circle
			(at -0.40005 0)
			(size 0 0)
			(layers "F.Cu" "F.Mask" "F.Paste")
			(net "PEX3_P1V25_ADC_A0")
		)
		(pad "2" smd circle
			(at 0.40005 0)
			(size 0 0)
			(layers "F.Cu" "F.Mask" "F.Paste")
			(net "P3V3_AUX")
		)
	)
)
